# T6G (Grand Teton) — schematic netlist excerpt (pin names and nets, part order shuffled) for the footprints in the layout excerpt that follows; sources: Cadence DE-HDL packaged netlist, KiCad conversion of 04192023_DAF0TMB3IC0_F0TG_MB_C_brd_V02_OCP.brd

C2548  Q_CAP  22UF 4V 20% X6S  pkg C0402  page 70 : A = PVDDCR_SOC_P0 ; B = GND
C220  Q_CAP  100UF 4V 20% X6S  pkg C0805  page 323 : A = P0V9_CPU1_RT0_2A ; B = GND
R383  Q_RES  15 1% CHIP  pkg 0402LF  page 18 : A = M_I_CPU0_ALERT_N ; B = M_I_CPU0_ALERT_R_N

(kicad_pcb
	(version 20260206)
	(generator "pcbnew")
	(generator_version "10.0")
	(general
		(thickness 1.6)
		(legacy_teardrops no)
	)
	(paper "A4")
	(title_block
		(title "04192023_DAF0TMB3IC0_F0TG_MB_C_brd_V02_OCP.brd")
		(comment 1 "Grand Teton / footprints 5937-5939 of 8354")
	)
	(layers
		(0 "F.Cu" signal "TOP")
		(4 "In1.Cu" signal "GND")
		(6 "In2.Cu" signal "IN1")
		(8 "In3.Cu" signal "GND1")
		(10 "In4.Cu" signal "IN2")
		(12 "In5.Cu" signal "GND2")
		(14 "In6.Cu" signal "IN3")
		(16 "In7.Cu" signal "GND3")
		(18 "In8.Cu" signal "VCC")
		(20 "In9.Cu" signal "VCC1")
		(22 "In10.Cu" signal "GND4")
		(24 "In11.Cu" signal "IN4")
		(26 "In12.Cu" signal "GND5")
		(28 "In13.Cu" signal "IN5")
		(30 "In14.Cu" signal "GND6")
		(32 "In15.Cu" signal "IN6")
		(34 "In16.Cu" signal "GND7")
		(2 "B.Cu" signal "BOTTOM")
		(9 "F.Adhes" user "F.Adhesive")
		(11 "B.Adhes" user "B.Adhesive")
		(13 "F.Paste" user "Package Geometry/Pastemask Top")
		(15 "B.Paste" user "Package Geometry/Pastemask Bottom")
		(5 "F.SilkS" user "Ref Des/Silkscreen Top")
		(7 "B.SilkS" user "Ref Des/Silkscreen Bottom")
		(1 "F.Mask" user "Board Geometry/Soldermask Top")
		(3 "B.Mask" user "Board Geometry/Soldermask Bottom")
		(17 "Dwgs.User" user "User.Drawings")
		(19 "Cmts.User" user "User.Comments")
		(21 "Eco1.User" user "User.Eco1")
		(23 "Eco2.User" user "User.Eco2")
		(25 "Edge.Cuts" user "Board Geometry/Outline")
		(27 "Margin" user)
		(31 "F.CrtYd" user "Package Geometry/Place Bound Top")
		(29 "B.CrtYd" user "Package Geometry/Place Bound Bottom")
		(35 "F.Fab" user "Ref Des/Assembly Top")
		(33 "B.Fab" user "Ref Des/Assembly Bottom")
	)
	(footprint ""
		(layer "B.Cu")
		(at 69.861684 -391.81405 180)
		(property "Reference" "C220"
			(at 0 0 0)
			(layer "B.SilkS")
			(hide yes)
			(effects
				(font
					(size 1.27 1.27)
				)
				(justify mirror)
			)
		)
		(property "Value" ""
			(at 0 0 0)
			(layer "B.Fab")
			(effects
				(font
					(size 1.27 1.27)
				)
				(justify mirror)
			)
		)
		(duplicate_pad_numbers_are_jumpers no)
		(fp_line
			(start 1.524 0.762)
			(end 1.524 -0.762)
			(stroke
				(width 0.1524)
				(type default)
			)
			(layer "B.SilkS")
		)
		(fp_line
			(start 1.524 -0.762)
			(end -1.524 -0.762)
			(stroke
				(width 0.1524)
				(type default)
			)
			(layer "B.SilkS")
		)
		(fp_line
			(start -1.524 0.762)
			(end 1.524 0.762)
			(stroke
				(width 0.1524)
				(type default)
			)
			(layer "B.SilkS")
		)
		(fp_line
			(start -1.524 -0.762)
			(end -1.524 0.762)
			(stroke
				(width 0.1524)
				(type default)
			)
			(layer "B.SilkS")
		)
		(fp_line
			(start 1.1049 0.724916)
			(end -1.1049 0.724916)
			(stroke
				(width 0.1)
				(type default)
			)
			(layer "B.Fab")
		)
		(fp_line
			(start 1.1049 -0.724916)
			(end 1.1049 0.724916)
			(stroke
				(width 0.1)
				(type default)
			)
			(layer "B.Fab")
		)
		(fp_line
			(start -1.1049 0.724916)
			(end -1.1049 -0.724916)
			(stroke
				(width 0.1)
				(type default)
			)
			(layer "B.Fab")
		)
		(fp_line
			(start -1.1049 -0.724916)
			(end 1.1049 -0.724916)
			(stroke
				(width 0.1)
				(type default)
			)
			(layer "B.Fab")
		)
		(pad "1" smd rect
			(at 0.889 0 180)
			(size 1.016 1.27)
			(layers "B.Cu" "B.Mask" "B.Paste")
			(net "P0V9_CPU1_RT0_2A")
		)
		(pad "2" smd rect
			(at -0.889 0 180)
			(size 1.016 1.27)
			(layers "B.Cu" "B.Mask" "B.Paste")
			(net "GND")
		)
	)
	(footprint ""
		(layer "B.Cu")
		(at 430.55921 -244.08511)
		(property "Reference" "R383"
			(at 0 0 0)
			(layer "B.SilkS")
			(hide yes)
			(effects
				(font
					(size 1.27 1.27)
				)
				(justify mirror)
			)
		)
		(property "Value" ""
			(at 0 0 0)
			(layer "B.Fab")
			(effects
				(font
					(size 1.27 1.27)
				)
				(justify mirror)
			)
		)
		(duplicate_pad_numbers_are_jumpers no)
		(fp_line
			(start -0.7874 -0.4064)
			(end -0.7874 0.4064)
			(stroke
				(width 0.1524)
				(type default)
			)
			(layer "B.SilkS")
		)
		(fp_line
			(start -0.7874 0.4064)
			(end 0.7874 0.4064)
			(stroke
				(width 0.1524)
				(type default)
			)
			(layer "B.SilkS")
		)
		(fp_line
			(start 0.7874 -0.4064)
			(end -0.7874 -0.4064)
			(stroke
				(width 0.1524)
				(type default)
			)
			(layer "B.SilkS")
		)
		(fp_line
			(start 0.7874 0.4064)
			(end 0.7874 -0.4064)
			(stroke
				(width 0.1524)
				(type default)
			)
			(layer "B.SilkS")
		)
		(fp_line
			(start -0.67945 -0.3048)
			(end -0.67945 0.3048)
			(stroke
				(width 0.1)
				(type default)
			)
			(layer "B.Fab")
		)
		(fp_line
			(start -0.67945 0.3048)
			(end -0.120396 0.3048)
			(stroke
				(width 0.1)
				(type default)
			)
			(layer "B.Fab")
		)
		(fp_line
			(start -0.12065 -0.3048)
			(end -0.67945 -0.3048)
			(stroke
				(width 0.1)
				(type default)
			)
			(layer "B.Fab")
		)
		(fp_line
			(start -0.12065 -0.2794)
			(end -0.12065 -0.3048)
			(stroke
				(width 0.1)
				(type default)
			)
			(layer "B.Fab")
		)
		(fp_line
			(start -0.120396 0.2794)
			(end 0.12065 0.2794)
			(stroke
				(width 0.1)
				(type default)
			)
			(layer "B.Fab")
		)
		(fp_line
			(start -0.120396 0.3048)
			(end -0.120396 0.2794)
			(stroke
				(width 0.1)
				(type default)
			)
			(layer "B.Fab")
		)
		(fp_line
			(start 0.12065 -0.305054)
			(end 0.12065 -0.2794)
			(stroke
				(width 0.1)
				(type default)
			)
			(layer "B.Fab")
		)
		(fp_line
			(start 0.12065 -0.2794)
			(end -0.12065 -0.2794)
			(stroke
				(width 0.1)
				(type default)
			)
			(layer "B.Fab")
		)
		(fp_line
			(start 0.12065 0.2794)
			(end 0.12065 0.3048)
			(stroke
				(width 0.1)
				(type default)
			)
			(layer "B.Fab")
		)
		(fp_line
			(start 0.12065 0.3048)
			(end 0.67945 0.3048)
			(stroke
				(width 0.1)
				(type default)
			)
			(layer "B.Fab")
		)
		(fp_line
			(start 0.67945 -0.305054)
			(end 0.12065 -0.305054)
			(stroke
				(width 0.1)
				(type default)
			)
			(layer "B.Fab")
		)
		(fp_line
			(start 0.67945 0.3048)
			(end 0.67945 -0.305054)
			(stroke
				(width 0.1)
				(type default)
			)
			(layer "B.Fab")
		)
		(pad "1" smd circle
			(at 0.40005 0 180)
			(size 0 0)
			(layers "B.Cu" "B.Mask" "B.Paste")
			(net "M_I_CPU0_ALERT_N")
		)
		(pad "2" smd circle
			(at -0.40005 0 180)
			(size 0 0)
			(layers "B.Cu" "B.Mask" "B.Paste")
			(net "M_I_CPU0_ALERT_R_N")
		)
	)
	(footprint ""
		(layer "B.Cu")
		(at 372.313454 -261.046976)
		(property "Reference" "C2548"
			(at 0 0 0)
			(layer "B.SilkS")
			(hide yes)
			(effects
				(font
					(size 1.27 1.27)
				)
				(justify mirror)
			)
		)
		(property "Value" ""
			(at 0 0 0)
			(layer "B.Fab")
			(effects
				(font
					(size 1.27 1.27)
				)
				(justify mirror)
			)
		)
		(duplicate_pad_numbers_are_jumpers no)
		(fp_line
			(start -0.7874 -0.4064)
			(end -0.7874 0.4064)
			(stroke
				(width 0.1524)
				(type default)
			)
			(layer "B.SilkS")
		)
		(fp_line
			(start -0.7874 0.4064)
			(end 0.7874 0.4064)
			(stroke
				(width 0.1524)
				(type default)
			)
			(layer "B.SilkS")
		)
		(fp_line
			(start 0.7874 -0.4064)
			(end -0.7874 -0.4064)
			(stroke
				(width 0.1524)
				(type default)
			)
			(layer "B.SilkS")
		)
		(fp_line
			(start 0.7874 0.4064)
			(end 0.7874 -0.4064)
			(stroke
				(width 0.1524)
				(type default)
			)
			(layer "B.SilkS")
		)
		(fp_line
			(start -0.67945 -0.3048)
			(end -0.67945 0.3048)
			(stroke
				(width 0.1)
				(type default)
			)
			(layer "B.Fab")
		)
		(fp_line
			(start -0.67945 0.3048)
			(end -0.120396 0.3048)
			(stroke
				(width 0.1)
				(type default)
			)
			(layer "B.Fab")
		)
		(fp_line
			(start -0.12065 -0.3048)
			(end -0.67945 -0.3048)
			(stroke
				(width 0.1)
				(type default)
			)
			(layer "B.Fab")
		)
		(fp_line
			(start -0.12065 -0.2794)
			(end -0.12065 -0.3048)
			(stroke
				(width 0.1)
				(type default)
			)
			(layer "B.Fab")
		)
		(fp_line
			(start -0.120396 0.2794)
			(end 0.12065 0.2794)
			(stroke
				(width 0.1)
				(type default)
			)
			(layer "B.Fab")
		)
		(fp_line
			(start -0.120396 0.3048)
			(end -0.120396 0.2794)
			(stroke
				(width 0.1)
				(type default)
			)
			(layer "B.Fab")
		)
		(fp_line
			(start 0.12065 -0.305054)
			(end 0.12065 -0.2794)
			(stroke
				(width 0.1)
				(type default)
			)
			(layer "B.Fab")
		)
		(fp_line
			(start 0.12065 -0.2794)
			(end -0.12065 -0.2794)
			(stroke
				(width 0.1)
				(type default)
			)
			(layer "B.Fab")
		)
		(fp_line
			(start 0.12065 0.2794)
			(end 0.12065 0.3048)
			(stroke
				(width 0.1)
				(type default)
			)
			(layer "B.Fab")
		)
		(fp_line
			(start 0.12065 0.3048)
			(end 0.67945 0.3048)
			(stroke
				(width 0.1)
				(type default)
			)
			(layer "B.Fab")
		)
		(fp_line
			(start 0.67945 -0.305054)
			(end 0.12065 -0.305054)
			(stroke
				(width 0.1)
				(type default)
			)
			(layer "B.Fab")
		)
		(fp_line
			(start 0.67945 0.3048)
			(end 0.67945 -0.305054)
			(stroke
				(width 0.1)
				(type default)
			)
			(layer "B.Fab")
		)
		(pad "1" smd circle
			(at 0.40005 0 180)
			(size 0 0)
			(layers "B.Cu" "B.Mask" "B.Paste")
			(net "PVDDCR_SOC_P0")
		)
		(pad "2" smd circle
			(at -0.40005 0 180)
			(size 0 0)
			(layers "B.Cu" "B.Mask" "B.Paste")
			(net "GND")
		)
	)
)
